# S9S_MB_2U (Grand Teton) — schematic netlist excerpt (pin names and nets, part order shuffled) for the footprints in the layout excerpt that follows; sources: Cadence DE-HDL packaged netlist, KiCad conversion of 03242023_DA0F0TMBIJ0_F0T_Motherboard_J_brd_V01_OCP.brd

PR3791  Q_RES  15K 1% CHIP  pkg 0402LF  page 156 : A = P3V3_OCP_OV_1 ; B = GND
C1530  Q_CAP_DIFFBUS  DIFF BUS_0.22UF 6.3V 20% X6S  pkg C0201  page 177 : \1\ = P5E_CPU1_PE3_TX_C_DN<8> ; \2\ = P5E_CPU1_PE3_TX_DN<8>
C768  Q_CAP_DIFFBUS  DIFF BUS_0.22UF 6.3V 20% X6S  pkg C0201  page 176 : \1\ = P5E_CPU1_PE2_TX_C_DN<2> ; \2\ = P5E_CPU1_PE2_TX_DN<2>

(kicad_pcb
	(version 20260206)
	(generator "pcbnew")
	(generator_version "10.0")
	(general
		(thickness 1.6)
		(legacy_teardrops no)
	)
	(paper "A4")
	(title_block
		(title "03242023_DA0F0TMBIJ0_F0T_Motherboard_J_brd_V01_OCP.brd")
		(comment 1 "Grand Teton / footprints 653-655 of 6105")
	)
	(layers
		(0 "F.Cu" signal "TOP")
		(4 "In1.Cu" signal "GND")
		(6 "In2.Cu" signal "IN1")
		(8 "In3.Cu" signal "GND1")
		(10 "In4.Cu" signal "IN2")
		(12 "In5.Cu" signal "GND2")
		(14 "In6.Cu" signal "IN3")
		(16 "In7.Cu" signal "GND3")
		(18 "In8.Cu" signal "VCC")
		(20 "In9.Cu" signal "VCC1")
		(22 "In10.Cu" signal "GND4")
		(24 "In11.Cu" signal "IN4")
		(26 "In12.Cu" signal "GND5")
		(28 "In13.Cu" signal "IN5")
		(30 "In14.Cu" signal "GND6")
		(32 "In15.Cu" signal "IN6")
		(34 "In16.Cu" signal "GND7")
		(2 "B.Cu" signal "BOTTOM")
		(9 "F.Adhes" user "F.Adhesive")
		(11 "B.Adhes" user "B.Adhesive")
		(13 "F.Paste" user "Package Geometry/Pastemask Top")
		(15 "B.Paste" user "Package Geometry/Pastemask Bottom")
		(5 "F.SilkS" user "Ref Des/Silkscreen Top")
		(7 "B.SilkS" user "Ref Des/Silkscreen Bottom")
		(1 "F.Mask" user "Board Geometry/Soldermask Top")
		(3 "B.Mask" user "Board Geometry/Soldermask Bottom")
		(17 "Dwgs.User" user "User.Drawings")
		(19 "Cmts.User" user "User.Comments")
		(21 "Eco1.User" user "User.Eco1")
		(23 "Eco2.User" user "User.Eco2")
		(25 "Edge.Cuts" user "Board Geometry/Outline")
		(27 "Margin" user)
		(31 "F.CrtYd" user "Package Geometry/Place Bound Top")
		(29 "B.CrtYd" user "Package Geometry/Place Bound Bottom")
		(35 "F.Fab" user "Ref Des/Assembly Top")
		(33 "B.Fab" user "Ref Des/Assembly Bottom")
	)
	(footprint ""
		(layer "F.Cu")
		(at 428.283116 -109.26699 90)
		(property "Reference" "PR3791"
			(at 0 0 90)
			(layer "F.SilkS")
			(hide yes)
			(effects
				(font
					(size 1.27 1.27)
				)
			)
		)
		(property "Value" ""
			(at 0 0 90)
			(layer "F.Fab")
			(effects
				(font
					(size 1.27 1.27)
				)
			)
		)
		(duplicate_pad_numbers_are_jumpers no)
		(fp_line
			(start 0.7874 -0.4064)
			(end 0.7874 0.4064)
			(stroke
				(width 0.1524)
				(type default)
			)
			(layer "F.SilkS")
		)
		(fp_line
			(start -0.7874 -0.4064)
			(end 0.7874 -0.4064)
			(stroke
				(width 0.1524)
				(type default)
			)
			(layer "F.SilkS")
		)
		(fp_line
			(start 0.7874 0.4064)
			(end -0.7874 0.4064)
			(stroke
				(width 0.1524)
				(type default)
			)
			(layer "F.SilkS")
		)
		(fp_line
			(start -0.7874 0.4064)
			(end -0.7874 -0.4064)
			(stroke
				(width 0.1524)
				(type default)
			)
			(layer "F.SilkS")
		)
		(fp_line
			(start -0.12065 -0.305054)
			(end -0.12065 -0.2794)
			(stroke
				(width 0.1)
				(type default)
			)
			(layer "F.Fab")
		)
		(fp_line
			(start -0.67945 -0.305054)
			(end -0.12065 -0.305054)
			(stroke
				(width 0.1)
				(type default)
			)
			(layer "F.Fab")
		)
		(fp_line
			(start 0.67945 -0.3048)
			(end 0.67945 0.3048)
			(stroke
				(width 0.1)
				(type default)
			)
			(layer "F.Fab")
		)
		(fp_line
			(start 0.12065 -0.3048)
			(end 0.67945 -0.3048)
			(stroke
				(width 0.1)
				(type default)
			)
			(layer "F.Fab")
		)
		(fp_line
			(start 0.12065 -0.2794)
			(end 0.12065 -0.3048)
			(stroke
				(width 0.1)
				(type default)
			)
			(layer "F.Fab")
		)
		(fp_line
			(start -0.12065 -0.2794)
			(end 0.12065 -0.2794)
			(stroke
				(width 0.1)
				(type default)
			)
			(layer "F.Fab")
		)
		(fp_line
			(start 0.120396 0.2794)
			(end -0.12065 0.2794)
			(stroke
				(width 0.1)
				(type default)
			)
			(layer "F.Fab")
		)
		(fp_line
			(start -0.12065 0.2794)
			(end -0.12065 0.3048)
			(stroke
				(width 0.1)
				(type default)
			)
			(layer "F.Fab")
		)
		(fp_line
			(start 0.67945 0.3048)
			(end 0.120396 0.3048)
			(stroke
				(width 0.1)
				(type default)
			)
			(layer "F.Fab")
		)
		(fp_line
			(start 0.120396 0.3048)
			(end 0.120396 0.2794)
			(stroke
				(width 0.1)
				(type default)
			)
			(layer "F.Fab")
		)
		(fp_line
			(start -0.12065 0.3048)
			(end -0.67945 0.3048)
			(stroke
				(width 0.1)
				(type default)
			)
			(layer "F.Fab")
		)
		(fp_line
			(start -0.67945 0.3048)
			(end -0.67945 -0.305054)
			(stroke
				(width 0.1)
				(type default)
			)
			(layer "F.Fab")
		)
		(pad "1" smd circle
			(at -0.40005 0 90)
			(size 0 0)
			(layers "F.Cu" "F.Mask" "F.Paste")
			(net "P3V3_OCP_OV_1")
		)
		(pad "2" smd circle
			(at 0.40005 0 90)
			(size 0 0)
			(layers "F.Cu" "F.Mask" "F.Paste")
			(net "GND")
		)
	)
	(footprint ""
		(layer "F.Cu")
		(at 160.866074 -402.371052 -90)
		(property "Reference" "C768"
			(at 0 0 270)
			(layer "F.SilkS")
			(hide yes)
			(effects
				(font
					(size 1.27 1.27)
				)
			)
		)
		(property "Value" ""
			(at 0 0 270)
			(layer "F.Fab")
			(effects
				(font
					(size 1.27 1.27)
				)
			)
		)
		(duplicate_pad_numbers_are_jumpers no)
		(fp_line
			(start -0.299974 0.150114)
			(end -0.299974 -0.150114)
			(stroke
				(width 0.1)
				(type default)
			)
			(layer "F.Fab")
		)
		(fp_line
			(start 0.299974 0.150114)
			(end -0.299974 0.150114)
			(stroke
				(width 0.1)
				(type default)
			)
			(layer "F.Fab")
		)
		(fp_line
			(start -0.299974 -0.150114)
			(end 0.299974 -0.150114)
			(stroke
				(width 0.1)
				(type default)
			)
			(layer "F.Fab")
		)
		(fp_line
			(start 0.299974 -0.150114)
			(end 0.299974 0.150114)
			(stroke
				(width 0.1)
				(type default)
			)
			(layer "F.Fab")
		)
		(pad "1" smd rect
			(at -0.2667 0 270)
			(size 0.3048 0.381)
			(layers "F.Cu" "F.Mask" "F.Paste")
			(net "P5E_CPU1_PE2_TX_C_DN<2>")
		)
		(pad "2" smd rect
			(at 0.2667 0 270)
			(size 0.3048 0.381)
			(layers "F.Cu" "F.Mask" "F.Paste")
			(net "P5E_CPU1_PE2_TX_DN<2>")
		)
	)
	(footprint ""
		(layer "F.Cu")
		(at 142.918434 -408.517344 -90)
		(property "Reference" "C1530"
			(at 0 0 270)
			(layer "F.SilkS")
			(hide yes)
			(effects
				(font
					(size 1.27 1.27)
				)
			)
		)
		(property "Value" ""
			(at 0 0 270)
			(layer "F.Fab")
			(effects
				(font
					(size 1.27 1.27)
				)
			)
		)
		(duplicate_pad_numbers_are_jumpers no)
		(fp_line
			(start -0.299974 0.150114)
			(end -0.299974 -0.150114)
			(stroke
				(width 0.1)
				(type default)
			)
			(layer "F.Fab")
		)
		(fp_line
			(start 0.299974 0.150114)
			(end -0.299974 0.150114)
			(stroke
				(width 0.1)
				(type default)
			)
			(layer "F.Fab")
		)
		(fp_line
			(start -0.299974 -0.150114)
			(end 0.299974 -0.150114)
			(stroke
				(width 0.1)
				(type default)
			)
			(layer "F.Fab")
		)
		(fp_line
			(start 0.299974 -0.150114)
			(end 0.299974 0.150114)
			(stroke
				(width 0.1)
				(type default)
			)
			(layer "F.Fab")
		)
		(pad "1" smd rect
			(at -0.2667 0 270)
			(size 0.3048 0.381)
			(layers "F.Cu" "F.Mask" "F.Paste")
			(net "P5E_CPU1_PE3_TX_C_DN<8>")
		)
		(pad "2" smd rect
			(at 0.2667 0 270)
			(size 0.3048 0.381)
			(layers "F.Cu" "F.Mask" "F.Paste")
			(net "P5E_CPU1_PE3_TX_DN<8>")
		)
	)
)
